(kicad_pcb
	(version 20241229)
	(generator "pcbnew")
	(generator_version "9.0")
	(general
		(thickness 1.711)
		(legacy_teardrops no)
	)
	(paper "A4")
	(title_block
		(title "Antmicro Baseboard for Jetson AGX Thor")
		(date "2026-02-18")
		(rev "1.1.0")
		(company "Antmicro Ltd")
		(comment 1 "www.antmicro.com")
		(comment 9 "footprints 471-475 of 1170")
	)
	(layers
		(0 "F.Cu" signal)
		(4 "In1.Cu" signal)
		(6 "In2.Cu" signal)
		(8 "In3.Cu" signal)
		(10 "In4.Cu" jumper)
		(12 "In5.Cu" signal)
		(14 "In6.Cu" signal)
		(16 "In7.Cu" signal)
		(18 "In8.Cu" signal)
		(2 "B.Cu" signal)
		(9 "F.Adhes" user "F.Adhesive")
		(11 "B.Adhes" user "B.Adhesive")
		(13 "F.Paste" user)
		(15 "B.Paste" user)
		(5 "F.SilkS" user "F.Silkscreen")
		(7 "B.SilkS" user "B.Silkscreen")
		(1 "F.Mask" user)
		(3 "B.Mask" user)
		(17 "Dwgs.User" user "User.Drawings")
		(19 "Cmts.User" user "User.Comments")
		(21 "Eco1.User" user "User.Eco1")
		(23 "Eco2.User" user "User.Eco2")
		(25 "Edge.Cuts" user)
		(27 "Margin" user)
		(31 "F.CrtYd" user "F.Courtyard")
		(29 "B.CrtYd" user "B.Courtyard")
		(35 "F.Fab" user)
		(33 "B.Fab" user)
	)
	(footprint "antmicro-footprints:R_0402_1005Metric"
		(layer "F.Cu")
		(at 88 59.5 180)
		(descr "Resistor SMD 0402")
		(tags "resistor SMD 0402")
		(property "Reference" "R302"
			(at 16.3 -8.8 0)
			(layer "F.SilkS")
			(effects
				(font
					(size 0.7 0.7)
					(thickness 0.15)
				)
				(justify right top)
			)
		)
		(property "Value" "R_0R_0402"
			(at -1.011843 1.772047 0)
			(layer "F.Fab")
			(effects
				(font
					(size 0.7 0.7)
					(thickness 0.15)
				)
				(justify right top)
			)
		)
		(property "Datasheet" "https://industrial.panasonic.com/cdbs/www-data/pdf/RDA0000/AOA0000C301.pdf"
			(at 0 0 0)
			(layer "F.Fab")
			(hide yes)
			(effects
				(font
					(size 1.27 1.27)
					(thickness 0.15)
				)
			)
		)
		(property "Description" "SMD Chip Resistor, Jumper, 0 ohm, 100 mW, 0402 [1005 Metric], Thick Film, General Purpose"
			(at 0 0 0)
			(layer "F.Fab")
			(hide yes)
			(effects
				(font
					(size 1.27 1.27)
					(thickness 0.15)
				)
			)
		)
		(property "MPN" "ERJ2GE0R00X"
			(at 0 0 180)
			(unlocked yes)
			(layer "F.Fab")
			(hide yes)
			(effects
				(font
					(size 1 1)
					(thickness 0.15)
				)
			)
		)
		(property "Manufacturer" "Panasonic"
			(at 0 0 180)
			(unlocked yes)
			(layer "F.Fab")
			(hide yes)
			(effects
				(font
					(size 1 1)
					(thickness 0.15)
				)
			)
		)
		(property "License" "Apache-2.0"
			(at 0 0 180)
			(unlocked yes)
			(layer "F.Fab")
			(hide yes)
			(effects
				(font
					(size 1 1)
					(thickness 0.15)
				)
			)
		)
		(property "Author" "Antmicro"
			(at 0 0 180)
			(unlocked yes)
			(layer "F.Fab")
			(hide yes)
			(effects
				(font
					(size 1 1)
					(thickness 0.15)
				)
			)
		)
		(property "Val" "0R"
			(at 0 0 180)
			(unlocked yes)
			(layer "F.Fab")
			(hide yes)
			(effects
				(font
					(size 1 1)
					(thickness 0.15)
				)
			)
		)
		(property "Tolerance" "~"
			(at 0 0 180)
			(unlocked yes)
			(layer "F.Fab")
			(hide yes)
			(effects
				(font
					(size 1 1)
					(thickness 0.15)
				)
			)
		)
		(property "Current" "1A"
			(at 0 0 180)
			(unlocked yes)
			(layer "F.Fab")
			(hide yes)
			(effects
				(font
					(size 1 1)
					(thickness 0.15)
				)
			)
		)
		(sheetname "/SoM_Power/")
		(sheetfile "som_power.kicad_sch")
		(attr smd)
		(fp_rect
			(start -0.925 -0.47)
			(end 0.925 0.47)
			(stroke
				(width 0.05)
				(type default)
			)
			(fill no)
			(layer "F.CrtYd")
		)
		(fp_rect
			(start -0.5 -0.25)
			(end 0.5 0.25)
			(stroke
				(width 0.15)
				(type solid)
			)
			(fill no)
			(layer "F.Fab")
		)
		(fp_text user "Author: Antmicro"
			(at -0.95 4.169 0)
			(layer "F.Fab")
			(effects
				(font
					(size 0.7 0.7)
					(thickness 0.15)
				)
				(justify right top)
			)
		)
		(fp_text user "License: Apache-2.0"
			(at -0.95 5.169 0)
			(layer "F.Fab")
			(effects
				(font
					(size 0.7 0.7)
					(thickness 0.15)
				)
				(justify right top)
			)
		)
		(fp_text user "${REFERENCE}"
			(at -0.95 3.168 0)
			(layer "F.Fab")
			(effects
				(font
					(size 0.7 0.7)
					(thickness 0.15)
				)
				(justify right top)
			)
		)
		(pad "1" smd roundrect
			(at -0.48 0 180)
			(size 0.59 0.64)
			(layers "F.Cu" "F.Mask" "F.Paste")
			(roundrect_rratio 0.25)
			(net 1035 "Net-(U70-~{INT})")
			(pintype "passive")
		)
		(pad "2" smd roundrect
			(at 0.48 0 180)
			(size 0.59 0.64)
			(layers "F.Cu" "F.Mask" "F.Paste")
			(roundrect_rratio 0.25)
			(net 85 "/SoM_Power/~{SOM_POWER_BTN}")
			(pintype "passive")
		)
	)
	(footprint "antmicro-footprints:R_0402_1005Metric"
		(layer "F.Cu")
		(at 172.869468 117.806 90)
		(descr "Resistor SMD 0402")
		(tags "resistor SMD 0402")
		(property "Reference" "R315"
			(at 2.006 -5.869468 90)
			(layer "F.SilkS")
			(effects
				(font
					(size 0.7 0.7)
					(thickness 0.15)
				)
				(justify right top)
			)
		)
		(property "Value" "R_27R_0402"
			(at -1.011843 1.772047 90)
			(layer "F.Fab")
			(effects
				(font
					(size 0.7 0.7)
					(thickness 0.15)
				)
				(justify left bottom)
			)
		)
		(property "Datasheet" "https://www.bourns.com/docs/product-datasheets/cr.pdf"
			(at 0 0 90)
			(layer "F.Fab")
			(hide yes)
			(effects
				(font
					(size 1.27 1.27)
					(thickness 0.15)
				)
			)
		)
		(property "Description" "SMD Chip Resistor, 27 ohm, ± 1%, 63 mW, 0402 [1005 Metric], Thick Film, General Purpose"
			(at 0 0 90)
			(layer "F.Fab")
			(hide yes)
			(effects
				(font
					(size 1.27 1.27)
					(thickness 0.15)
				)
			)
		)
		(property "MPN" "CR0402-FX-27R0GLF"
			(at 0 0 90)
			(unlocked yes)
			(layer "F.Fab")
			(hide yes)
			(effects
				(font
					(size 1 1)
					(thickness 0.15)
				)
			)
		)
		(property "Manufacturer" "Bourns"
			(at 0 0 90)
			(unlocked yes)
			(layer "F.Fab")
			(hide yes)
			(effects
				(font
					(size 1 1)
					(thickness 0.15)
				)
			)
		)
		(property "License" "Apache-2.0"
			(at 0 0 90)
			(unlocked yes)
			(layer "F.Fab")
			(hide yes)
			(effects
				(font
					(size 1 1)
					(thickness 0.15)
				)
			)
		)
		(property "Author" "Antmicro"
			(at 0 0 90)
			(unlocked yes)
			(layer "F.Fab")
			(hide yes)
			(effects
				(font
					(size 1 1)
					(thickness 0.15)
				)
			)
		)
		(property "Val" "27R"
			(at 0 0 90)
			(unlocked yes)
			(layer "F.Fab")
			(hide yes)
			(effects
				(font
					(size 1 1)
					(thickness 0.15)
				)
			)
		)
		(property "Tolerance" "1%"
			(at 0 0 90)
			(unlocked yes)
			(layer "F.Fab")
			(hide yes)
			(effects
				(font
					(size 1 1)
					(thickness 0.15)
				)
			)
		)
		(sheetname "/DCDC/")
		(sheetfile "dcdc.kicad_sch")
		(attr smd)
		(fp_rect
			(start -0.925 -0.47)
			(end 0.925 0.47)
			(stroke
				(width 0.05)
				(type default)
			)
			(fill no)
			(layer "F.CrtYd")
		)
		(fp_rect
			(start -0.5 -0.25)
			(end 0.5 0.25)
			(stroke
				(width 0.15)
				(type solid)
			)
			(fill no)
			(layer "F.Fab")
		)
		(fp_text user "${REFERENCE}"
			(at -0.95 3.168 90)
			(layer "F.Fab")
			(effects
				(font
					(size 0.7 0.7)
					(thickness 0.15)
				)
				(justify left bottom)
			)
		)
		(fp_text user "License: Apache-2.0"
			(at -0.95 5.169 90)
			(layer "F.Fab")
			(effects
				(font
					(size 0.7 0.7)
					(thickness 0.15)
				)
				(justify left bottom)
			)
		)
		(fp_text user "Author: Antmicro"
			(at -0.95 4.169 90)
			(layer "F.Fab")
			(effects
				(font
					(size 0.7 0.7)
					(thickness 0.15)
				)
				(justify left bottom)
			)
		)
		(pad "1" smd roundrect
			(at -0.48 0 90)
			(size 0.59 0.64)
			(layers "F.Cu" "F.Mask" "F.Paste")
			(roundrect_rratio 0.25)
			(net 1281 "Net-(U50-IN+)")
			(pintype "passive")
		)
		(pad "2" smd roundrect
			(at 0.48 0 90)
			(size 0.59 0.64)
			(layers "F.Cu" "F.Mask" "F.Paste")
			(roundrect_rratio 0.25)
			(net 253 "/DCDC/5V_OUT")
			(pintype "passive")
		)
	)
	(footprint "antmicro-footprints:TP_SMD_0.75mm"
		(layer "F.Cu")
		(at 170.75 57.14 90)
		(property "Reference" "TP7"
			(at -1.52 -0.77 90)
			(layer "F.SilkS")
			(hide yes)
			(effects
				(font
					(size 0.7 0.7)
					(thickness 0.15)
				)
				(justify left bottom)
			)
		)
		(property "Value" "TP_0.75mm_SMD"
			(at 0 1.2 90)
			(layer "F.Fab")
			(effects
				(font
					(size 0.7 0.7)
					(thickness 0.15)
				)
				(justify left bottom)
			)
		)
		(property "Description" "SMT test point"
			(at 0 0 90)
			(layer "F.Fab")
			(hide yes)
			(effects
				(font
					(size 1.27 1.27)
					(thickness 0.15)
				)
			)
		)
		(property "MPN" ""
			(at 0 0 90)
			(unlocked yes)
			(layer "F.Fab")
			(hide yes)
			(effects
				(font
					(size 1 1)
					(thickness 0.15)
				)
			)
		)
		(property "Manufacturer" ""
			(at 0 0 90)
			(unlocked yes)
			(layer "F.Fab")
			(hide yes)
			(effects
				(font
					(size 1 1)
					(thickness 0.15)
				)
			)
		)
		(property "Author" "Antmicro"
			(at 0 0 90)
			(unlocked yes)
			(layer "F.Fab")
			(hide yes)
			(effects
				(font
					(size 1 1)
					(thickness 0.15)
				)
			)
		)
		(property "License" "Apache-2.0"
			(at 0 0 90)
			(unlocked yes)
			(layer "F.Fab")
			(hide yes)
			(effects
				(font
					(size 1 1)
					(thickness 0.15)
				)
			)
		)
		(sheetname "/Power/")
		(sheetfile "power.kicad_sch")
		(attr exclude_from_pos_files exclude_from_bom)
		(fp_circle
			(center 0 0)
			(end 0.475 0)
			(stroke
				(width 0.05)
				(type default)
			)
			(fill no)
			(layer "F.CrtYd")
		)
		(fp_text user "Author: Antmicro"
			(at -0.4 3.901 90)
			(layer "F.Fab")
			(effects
				(font
					(size 0.7 0.7)
					(thickness 0.15)
				)
				(justify left bottom)
			)
		)
		(fp_text user "${REFERENCE}"
			(at -0.4 2.7 90)
			(layer "F.Fab")
			(effects
				(font
					(size 0.7 0.7)
					(thickness 0.15)
				)
				(justify left bottom)
			)
		)
		(fp_text user "License: Apache-2.0"
			(at -0.4 5.101 90)
			(layer "F.Fab")
			(effects
				(font
					(size 0.7 0.7)
					(thickness 0.15)
				)
				(justify left bottom)
			)
		)
		(pad "1" smd circle
			(at 0 0 90)
			(size 0.75 0.75)
			(layers "F.Cu" "F.Mask")
			(net 5 "+5V")
			(pinfunction "1")
			(pintype "passive")
		)
	)
	(footprint "antmicro-footprints:QFN-2L_1.6x1x0.55mm"
		(layer "F.Cu")
		(at 168.4 147.62)
		(property "Reference" "D13"
			(at -0.9 -0.72 0)
			(layer "F.SilkS")
			(effects
				(font
					(size 0.7 0.7)
					(thickness 0.15)
				)
				(justify left bottom)
			)
		)
		(property "Value" "ESDA25P35-1U1M"
			(at 0 1.7 0)
			(layer "F.Fab")
			(effects
				(font
					(size 0.7 0.7)
					(thickness 0.15)
				)
				(justify left bottom)
			)
		)
		(property "Datasheet" "https://www.st.com/resource/en/datasheet/esda25p35-1u1m.pdf"
			(at 0 0 0)
			(layer "F.Fab")
			(hide yes)
			(effects
				(font
					(size 1.27 1.27)
					(thickness 0.15)
				)
			)
		)
		(property "Description" "Unidirectional TVS, 30 kV, QFN-2L, 22 V, 195 pF"
			(at 0 0 0)
			(layer "F.Fab")
			(hide yes)
			(effects
				(font
					(size 1.27 1.27)
					(thickness 0.15)
				)
			)
		)
		(property "Manufacturer" "STMicroelectronics"
			(at 0 0 0)
			(unlocked yes)
			(layer "F.Fab")
			(hide yes)
			(effects
				(font
					(size 1 1)
					(thickness 0.15)
				)
			)
		)
		(property "MPN" "ESDA25P35-1U1M"
			(at 0 0 0)
			(unlocked yes)
			(layer "F.Fab")
			(hide yes)
			(effects
				(font
					(size 1 1)
					(thickness 0.15)
				)
			)
		)
		(property "Author" "Antmicro"
			(at 0 0 0)
			(unlocked yes)
			(layer "F.Fab")
			(hide yes)
			(effects
				(font
					(size 1 1)
					(thickness 0.15)
				)
			)
		)
		(property "License" "Apache-2.0"
			(at 0 0 0)
			(unlocked yes)
			(layer "F.Fab")
			(hide yes)
			(effects
				(font
					(size 1 1)
					(thickness 0.15)
				)
			)
		)
		(sheetname "/DCDC/")
		(sheetfile "dcdc.kicad_sch")
		(attr smd)
		(fp_line
			(start -1.2 -0.4)
			(end -1.2 0.4)
			(stroke
				(width 0.15)
				(type solid)
			)
			(layer "F.SilkS")
		)
		(fp_line
			(start 0.23 -0.45)
			(end -0.23 -0.45)
			(stroke
				(width 0.15)
				(type solid)
			)
			(layer "F.SilkS")
		)
		(fp_line
			(start 0.23 0.45)
			(end -0.23 0.45)
			(stroke
				(width 0.15)
				(type solid)
			)
			(layer "F.SilkS")
		)
		(fp_rect
			(start 1.25 0.65)
			(end -1.25 -0.65)
			(stroke
				(width 0.05)
				(type solid)
			)
			(fill no)
			(layer "F.CrtYd")
		)
		(fp_line
			(start -0.199 -0.202)
			(end -0.199 0.1)
			(stroke
				(width 0.15)
				(type solid)
			)
			(layer "F.Fab")
		)
		(fp_line
			(start -0.199 0)
			(end -0.597 0)
			(stroke
				(width 0.15)
				(type solid)
			)
			(layer "F.Fab")
		)
		(fp_line
			(start -0.199 0.2)
			(end -0.199 0.1)
			(stroke
				(width 0.15)
				(type solid)
			)
			(layer "F.Fab")
		)
		(fp_line
			(start -0.101 0)
			(end 0.201 0.2)
			(stroke
				(width 0.15)
				(type solid)
			)
			(layer "F.Fab")
		)
		(fp_line
			(start 0.201 -0.202)
			(end -0.101 0)
			(stroke
				(width 0.15)
				(type solid)
			)
			(layer "F.Fab")
		)
		(fp_line
			(start 0.201 0)
			(end 0.201 -0.202)
			(stroke
				(width 0.15)
				(type solid)
			)
			(layer "F.Fab")
		)
		(fp_line
			(start 0.201 0.2)
			(end 0.201 0)
			(stroke
				(width 0.15)
				(type solid)
			)
			(layer "F.Fab")
		)
		(fp_line
			(start 0.599 0)
			(end 0.201 0)
			(stroke
				(width 0.15)
				(type solid)
			)
			(layer "F.Fab")
		)
		(fp_rect
			(start 0.848 0.4)
			(end -0.85 -0.402)
			(stroke
				(width 0.15)
				(type solid)
			)
			(fill no)
			(layer "F.Fab")
		)
		(fp_text user "${REFERENCE}"
			(at -1.31 3.769 0)
			(layer "F.Fab")
			(effects
				(font
					(size 0.7 0.7)
					(thickness 0.15)
				)
				(justify left bottom)
			)
		)
		(fp_text user "Author: Antmicro"
			(at -1.31 4.769 0)
			(layer "F.Fab")
			(effects
				(font
					(size 0.7 0.7)
					(thickness 0.15)
				)
				(justify left bottom)
			)
		)
		(fp_text user "License: Apache-2.0"
			(at -1.31 5.769 0)
			(layer "F.Fab")
			(effects
				(font
					(size 0.7 0.7)
					(thickness 0.15)
				)
				(justify left bottom)
			)
		)
		(pad "1" smd roundrect
			(at -0.7 0 180)
			(size 0.8 1)
			(layers "F.Cu" "F.Mask" "F.Paste")
			(roundrect_rratio 0.2)
			(net 634 "+12V")
			(pinfunction "C")
			(pintype "passive")
		)
		(pad "2" smd roundrect
			(at 0.7 0 180)
			(size 0.8 1)
			(layers "F.Cu" "F.Mask" "F.Paste")
			(roundrect_rratio 0.2)
			(net 1 "GND")
			(pinfunction "A")
			(pintype "passive")
		)
	)
	(footprint "antmicro-footprints:R_0402_1005Metric"
		(layer "F.Cu")
		(at 179.146569 123.837356 180)
		(descr "Resistor SMD 0402")
		(tags "resistor SMD 0402")
		(property "Reference" "R38"
			(at -0.95 1.25 0)
			(layer "F.SilkS")
			(effects
				(font
					(size 0.7 0.7)
					(thickness 0.15)
				)
				(justify right top)
			)
		)
		(property "Value" "R_499k_0402"
			(at -1.011843 1.772047 0)
			(layer "F.Fab")
			(effects
				(font
					(size 0.7 0.7)
					(thickness 0.15)
				)
				(justify right top)
			)
		)
		(property "Datasheet" "https://www.mouser.com/datasheet/2/54/cr-1858361.pdf"
			(at 0 0 0)
			(layer "F.Fab")
			(hide yes)
			(effects
				(font
					(size 1.27 1.27)
					(thickness 0.15)
				)
			)
		)
		(property "Description" "SMD Chip Resistor, 499 kohm, ± 1%, 63 mW, 0402 [1005 Metric], Thick Film, General Purpose"
			(at 0 0 0)
			(layer "F.Fab")
			(hide yes)
			(effects
				(font
					(size 1.27 1.27)
					(thickness 0.15)
				)
			)
		)
		(property "MPN" "CR0402-FX-4993GLF"
			(at 0 0 180)
			(unlocked yes)
			(layer "F.Fab")
			(hide yes)
			(effects
				(font
					(size 1 1)
					(thickness 0.15)
				)
			)
		)
		(property "Manufacturer" "Bourns"
			(at 0 0 180)
			(unlocked yes)
			(layer "F.Fab")
			(hide yes)
			(effects
				(font
					(size 1 1)
					(thickness 0.15)
				)
			)
		)
		(property "License" "Apache-2.0"
			(at 0 0 180)
			(unlocked yes)
			(layer "F.Fab")
			(hide yes)
			(effects
				(font
					(size 1 1)
					(thickness 0.15)
				)
			)
		)
		(property "Author" "Antmicro"
			(at 0 0 180)
			(unlocked yes)
			(layer "F.Fab")
			(hide yes)
			(effects
				(font
					(size 1 1)
					(thickness 0.15)
				)
			)
		)
		(property "Val" "499k"
			(at 0 0 180)
			(unlocked yes)
			(layer "F.Fab")
			(hide yes)
			(effects
				(font
					(size 1 1)
					(thickness 0.15)
				)
			)
		)
		(property "Tolerance" "1%"
			(at 0 0 180)
			(unlocked yes)
			(layer "F.Fab")
			(hide yes)
			(effects
				(font
					(size 1 1)
					(thickness 0.15)
				)
			)
		)
		(sheetname "/DCDC/")
		(sheetfile "dcdc.kicad_sch")
		(attr smd exclude_from_pos_files exclude_from_bom dnp)
		(fp_rect
			(start -0.925 -0.47)
			(end 0.925 0.47)
			(stroke
				(width 0.05)
				(type default)
			)
			(fill no)
			(layer "F.CrtYd")
		)
		(fp_rect
			(start -0.5 -0.25)
			(end 0.5 0.25)
			(stroke
				(width 0.15)
				(type solid)
			)
			(fill no)
			(layer "F.Fab")
		)
		(fp_text user "Author: Antmicro"
			(at -0.95 4.169 0)
			(layer "F.Fab")
			(effects
				(font
					(size 0.7 0.7)
					(thickness 0.15)
				)
				(justify right top)
			)
		)
		(fp_text user "${REFERENCE}"
			(at -0.95 3.168 0)
			(layer "F.Fab")
			(effects
				(font
					(size 0.7 0.7)
					(thickness 0.15)
				)
				(justify right top)
			)
		)
		(fp_text user "License: Apache-2.0"
			(at -0.95 5.169 0)
			(layer "F.Fab")
			(effects
				(font
					(size 0.7 0.7)
					(thickness 0.15)
				)
				(justify right top)
			)
		)
		(pad "1" smd roundrect
			(at -0.48 0 180)
			(size 0.59 0.64)
			(layers "F.Cu" "F.Mask" "F.Paste")
			(roundrect_rratio 0.25)
			(net 1213 "/DCDC/3V3_MODE1")
			(pintype "passive")
		)
		(pad "2" smd roundrect
			(at 0.48 0 180)
			(size 0.59 0.64)
			(layers "F.Cu" "F.Mask" "F.Paste")
			(roundrect_rratio 0.25)
			(net 19 "/DCDC/3V3_VDD")
			(pintype "passive")
		)
	)
)
